(kicad_pcb
	(version 20211014)
	(generator pcbnew)
	(general
    (thickness 1.6)
  )
	(paper "A4")
	(title_block
    (title "SA800U (Snapdragon 845) Baseboard")
    (date "2023-10-19")
    (rev "1.0.3")
    (company "Antmicro Ltd.")
    (comment 1 "www.antmicro.com")
		(comment 9 "footprints 48-56 of 589")
	)
	(layers
    (0 "F.Cu" signal)
    (1 "In1.Cu" power)
    (2 "In2.Cu" signal)
    (3 "In3.Cu" signal)
    (4 "In4.Cu" power)
    (31 "B.Cu" signal)
    (32 "B.Adhes" user "B.Adhesive")
    (33 "F.Adhes" user "F.Adhesive")
    (34 "B.Paste" user)
    (35 "F.Paste" user)
    (36 "B.SilkS" user "B.Silkscreen")
    (37 "F.SilkS" user "F.Silkscreen")
    (38 "B.Mask" user)
    (39 "F.Mask" user)
    (40 "Dwgs.User" user "User.Drawings")
    (41 "Cmts.User" user "User.Comments")
    (42 "Eco1.User" user "User.Eco1")
    (43 "Eco2.User" user "User.Eco2")
    (44 "Edge.Cuts" user)
    (45 "Margin" user)
    (46 "B.CrtYd" user "B.Courtyard")
    (47 "F.CrtYd" user "F.Courtyard")
    (48 "B.Fab" user)
    (49 "F.Fab" user)
  )
	(footprint "sa800u-baseboard-hw-footprints:R_0402_1005Metric" (layer "F.Cu")
    (tedit 5FD9C158)
    (at 73.525 115.3 180)
    (descr "Resistor SMD 0402")
    (tags "resistor SMD 0402")
    (property "Author" "Antmicro")
    (property "DNP" "DNP")
    (property "License" "Apache-2.0")
    (property "MPN" "CR0402-FX-1002GLF")
    (property "Manufacturer" "Bourns")
    (property "Sheetfile" "psu.kicad_sch")
    (property "Sheetname" "PSU")
    (property "Tolerance" "1%")
    (property "Val" "10k")
    (attr exclude_from_pos_files)
    (fp_text reference "R134" (at -1.605 -5.86 180) (layer "F.SilkS")
      (effects (font (size 0.7 0.7) (thickness 0.15)) (justify left bottom))
    )
    (fp_text value "R_10k_0402" (at 0 1.4 180) (layer "F.Fab")
      (effects (font (size 0.7 0.7) (thickness 0.15)) (justify left bottom))
    )
    (fp_text user "Author: Antmicro" (at -0.95 4.169 180) (layer "F.Fab") hide
      (effects (font (size 0.7 0.7) (thickness 0.15)) (justify left bottom))
    )
    (fp_text user "${REFERENCE}" (at -0.95 3.168 180) (layer "F.Fab") hide
      (effects (font (size 0.7 0.7) (thickness 0.15)) (justify left bottom))
    )
    (fp_text user "License: Apache-2.0" (at -0.95 5.169 180) (layer "F.Fab") hide
      (effects (font (size 0.7 0.7) (thickness 0.15)) (justify left bottom))
    )
    (fp_rect (start -0.93 -0.47) (end 0.93 0.47) (layer "F.CrtYd") (width 0.05) (fill none))
    (fp_rect (start -0.5 -0.25) (end 0.5 0.25) (layer "F.Fab") (width 0.15) (fill none))
    (pad "1" smd roundrect (at -0.485 0 180) (size 0.59 0.64) (layers "F.Cu" "F.Paste" "F.Mask") (roundrect_rratio 0.25)
      (net 74 "VDD") (pintype "passive"))
    (pad "2" smd roundrect (at 0.485 0 180) (size 0.59 0.64) (layers "F.Cu" "F.Paste" "F.Mask") (roundrect_rratio 0.25)
      (net 164 "/PSU/5V_DC_DC_ENABLE") (pintype "passive"))
  )
	(footprint "sa800u-baseboard-hw-footprints:R_0402_1005Metric" (layer "F.Cu")
    (tedit 5FD9C158)
    (at 73.6 109.45 180)
    (descr "Resistor SMD 0402")
    (tags "resistor SMD 0402")
    (property "Author" "Antmicro")
    (property "DNP" "DNP")
    (property "License" "Apache-2.0")
    (property "MPN" "CR0402-FX-1002GLF")
    (property "Manufacturer" "Bourns")
    (property "Sheetfile" "psu.kicad_sch")
    (property "Sheetname" "PSU")
    (property "Tolerance" "1%")
    (property "Val" "10k")
    (attr exclude_from_pos_files)
    (fp_text reference "R132" (at 3.02 0.77 180) (layer "F.SilkS")
      (effects (font (size 0.7 0.7) (thickness 0.15)) (justify left bottom))
    )
    (fp_text value "R_10k_0402" (at 0 1.4 180) (layer "F.Fab")
      (effects (font (size 0.7 0.7) (thickness 0.15)) (justify left bottom))
    )
    (fp_text user "License: Apache-2.0" (at -0.95 5.169 180) (layer "F.Fab") hide
      (effects (font (size 0.7 0.7) (thickness 0.15)) (justify left bottom))
    )
    (fp_text user "Author: Antmicro" (at -0.95 4.169 180) (layer "F.Fab") hide
      (effects (font (size 0.7 0.7) (thickness 0.15)) (justify left bottom))
    )
    (fp_text user "${REFERENCE}" (at -0.95 3.168 180) (layer "F.Fab") hide
      (effects (font (size 0.7 0.7) (thickness 0.15)) (justify left bottom))
    )
    (fp_rect (start -0.93 -0.47) (end 0.93 0.47) (layer "F.CrtYd") (width 0.05) (fill none))
    (fp_rect (start -0.5 -0.25) (end 0.5 0.25) (layer "F.Fab") (width 0.15) (fill none))
    (pad "1" smd roundrect (at -0.485 0 180) (size 0.59 0.64) (layers "F.Cu" "F.Paste" "F.Mask") (roundrect_rratio 0.25)
      (net 74 "VDD") (pintype "passive"))
    (pad "2" smd roundrect (at 0.485 0 180) (size 0.59 0.64) (layers "F.Cu" "F.Paste" "F.Mask") (roundrect_rratio 0.25)
      (net 407 "Net-(R127-Pad2)") (pintype "passive"))
  )
	(footprint "sa800u-baseboard-hw-footprints:C_0402_1005Metric" (layer "F.Cu")
    (tedit 616D63CF)
    (at 145.2 96.9 180)
    (descr "Capacitor SMD 0402")
    (tags "capacitor SMD 0402")
    (property "Author" "Antmicro")
    (property "Dielectric" "X5R")
    (property "License" "Apache-2.0")
    (property "MPN" "GRM155R61H104KE14D")
    (property "Manufacturer" "Murata")
    (property "Sheetfile" "m2.kicad_sch")
    (property "Sheetname" "M2")
    (property "Val" "100n")
    (property "Voltage" "50V")
    (attr smd)
    (fp_text reference "C115" (at 3.74 -0.37 180) (layer "F.SilkS")
      (effects (font (size 0.7 0.7) (thickness 0.15)) (justify left bottom))
    )
    (fp_text value "C_100n_0402" (at 0 1.4 180) (layer "F.Fab")
      (effects (font (size 0.7 0.7) (thickness 0.15)) (justify left bottom))
    )
    (fp_text user "Author: Antmicro" (at -0.932 4.17 180) (layer "F.Fab") hide
      (effects (font (size 0.7 0.7) (thickness 0.15)) (justify left bottom))
    )
    (fp_text user "${REFERENCE}" (at -0.932 3.168 180) (layer "F.Fab") hide
      (effects (font (size 0.7 0.7) (thickness 0.15)) (justify left bottom))
    )
    (fp_text user "License: Apache-2.0" (at -0.932 5.17 180) (layer "F.Fab") hide
      (effects (font (size 0.7 0.7) (thickness 0.15)) (justify left bottom))
    )
    (fp_rect (start -0.94 -0.47) (end 0.94 0.47) (layer "F.CrtYd") (width 0.05) (fill none))
    (fp_rect (start -0.499 -0.249) (end 0.499 0.249) (layer "F.Fab") (width 0.15) (fill none))
    (pad "1" smd roundrect (at -0.484 0 180) (size 0.59 0.64) (layers "F.Cu" "F.Paste" "F.Mask") (roundrect_rratio 0.25)
      (net 109 "/M2/C_PCIE0_TX0_P") (pintype "passive"))
    (pad "2" smd roundrect (at 0.484 0 180) (size 0.59 0.64) (layers "F.Cu" "F.Paste" "F.Mask") (roundrect_rratio 0.25)
      (net 108 "PCIE0_TX_P") (pintype "passive"))
  )
	(footprint "sa800u-baseboard-hw-footprints:C_0805_2012Metric" (layer "F.Cu")
    (tedit 5FD9C126)
    (at 123.7 105.05)
    (descr "Capacitor SMD 0805")
    (tags "capacitor SMD 0805")
    (property "Author" "Antmicro")
    (property "DNP" "DNP")
    (property "Dielectric" "")
    (property "License" "Apache-2.0")
    (property "MPN" "0805X475K250CT")
    (property "Manufacturer" "Walsin")
    (property "Sheetfile" "camera-interface.kicad_sch")
    (property "Sheetname" "Camera Interface")
    (property "Val" "4u7")
    (property "Voltage" "")
    (attr exclude_from_pos_files)
    (fp_text reference "C105" (at 1.88 0.33) (layer "F.SilkS")
      (effects (font (size 0.7 0.7) (thickness 0.15)) (justify left bottom))
    )
    (fp_text value "C_4u7_0805" (at 0 1.947) (layer "F.Fab")
      (effects (font (size 0.7 0.7) (thickness 0.15)) (justify left bottom))
    )
    (fp_text user "${REFERENCE}" (at -1.9 3.947) (layer "F.Fab") hide
      (effects (font (size 0.7 0.7) (thickness 0.15)) (justify left bottom))
    )
    (fp_text user "License: Apache-2.0" (at -1.9 4.947) (layer "F.Fab") hide
      (effects (font (size 0.7 0.7) (thickness 0.15)) (justify left bottom))
    )
    (fp_text user "Author: Antmicro" (at -1.9 5.947) (layer "F.Fab") hide
      (effects (font (size 0.7 0.7) (thickness 0.15)) (justify left bottom))
    )
    (fp_line (start -0.3 0.8) (end 0.3 0.8) (layer "F.SilkS") (width 0.15))
    (fp_line (start -0.3 -0.8) (end 0.3 -0.8) (layer "F.SilkS") (width 0.15))
    (fp_rect (start -1.9 -0.93) (end 1.9 0.93) (layer "F.CrtYd") (width 0.05) (fill none))
    (fp_rect (start -0.95 -0.675) (end 0.95 0.675) (layer "F.Fab") (width 0.15) (fill none))
    (pad "1" smd rect (at -1.05 0) (size 1.2 1.2) (layers "F.Cu" "F.Paste" "F.Mask")
      (net 133 "5V_SYS") (pintype "passive"))
    (pad "2" smd rect (at 1.05 0) (size 1.2 1.2) (layers "F.Cu" "F.Paste" "F.Mask")
      (net 1 "GND") (pintype "passive"))
  )
	(footprint "sa800u-baseboard-hw-footprints:C_0805_2012Metric" (layer "F.Cu")
    (tedit 5FD9C126)
    (at 117.1 104.9 180)
    (descr "Capacitor SMD 0805")
    (tags "capacitor SMD 0805")
    (property "Author" "Antmicro")
    (property "DNP" "DNP")
    (property "Dielectric" "")
    (property "License" "Apache-2.0")
    (property "MPN" "0805X475K250CT")
    (property "Manufacturer" "Walsin")
    (property "Sheetfile" "camera-interface.kicad_sch")
    (property "Sheetname" "Camera Interface")
    (property "Val" "4u7")
    (property "Voltage" "")
    (attr exclude_from_pos_files)
    (fp_text reference "C108" (at 4.76 -0.43 180) (layer "F.SilkS")
      (effects (font (size 0.7 0.7) (thickness 0.15)) (justify left bottom))
    )
    (fp_text value "C_4u7_0805" (at 0 1.947 180) (layer "F.Fab")
      (effects (font (size 0.7 0.7) (thickness 0.15)) (justify left bottom))
    )
    (fp_text user "${REFERENCE}" (at -1.9 3.947 180) (layer "F.Fab") hide
      (effects (font (size 0.7 0.7) (thickness 0.15)) (justify left bottom))
    )
    (fp_text user "License: Apache-2.0" (at -1.9 4.947 180) (layer "F.Fab") hide
      (effects (font (size 0.7 0.7) (thickness 0.15)) (justify left bottom))
    )
    (fp_text user "Author: Antmicro" (at -1.9 5.947 180) (layer "F.Fab") hide
      (effects (font (size 0.7 0.7) (thickness 0.15)) (justify left bottom))
    )
    (fp_line (start -0.3 -0.8) (end 0.3 -0.8) (layer "F.SilkS") (width 0.15))
    (fp_line (start -0.3 0.8) (end 0.3 0.8) (layer "F.SilkS") (width 0.15))
    (fp_rect (start -1.9 -0.93) (end 1.9 0.93) (layer "F.CrtYd") (width 0.05) (fill none))
    (fp_rect (start -0.95 -0.675) (end 0.95 0.675) (layer "F.Fab") (width 0.15) (fill none))
    (pad "1" smd rect (at -1.05 0 180) (size 1.2 1.2) (layers "F.Cu" "F.Paste" "F.Mask")
      (net 353 "Net-(C108-Pad1)") (pintype "passive"))
    (pad "2" smd rect (at 1.05 0 180) (size 1.2 1.2) (layers "F.Cu" "F.Paste" "F.Mask")
      (net 1 "GND") (pintype "passive"))
  )
	(footprint "sa800u-baseboard-hw-footprints:R_0402_1005Metric" (layer "F.Cu")
    (tedit 5FD9C158)
    (at 137.2 103 180)
    (descr "Resistor SMD 0402")
    (tags "resistor SMD 0402")
    (property "Author" "Antmicro")
    (property "License" "Apache-2.0")
    (property "MPN" "CR0402-FX-1001GLF")
    (property "Manufacturer" "Bourns")
    (property "Sheetfile" "som.kicad_sch")
    (property "Sheetname" "SoM")
    (property "Tolerance" "1%")
    (property "Val" "1k")
    (attr smd)
    (fp_text reference "R69" (at -0.81 -0.4 180) (layer "F.SilkS")
      (effects (font (size 0.7 0.7) (thickness 0.15)) (justify left bottom))
    )
    (fp_text value "R_1k_0402" (at 0 1.4 180) (layer "F.Fab")
      (effects (font (size 0.7 0.7) (thickness 0.15)) (justify left bottom))
    )
    (fp_text user "Author: Antmicro" (at -0.95 4.169 180) (layer "F.Fab") hide
      (effects (font (size 0.7 0.7) (thickness 0.15)) (justify left bottom))
    )
    (fp_text user "License: Apache-2.0" (at -0.95 5.169 180) (layer "F.Fab") hide
      (effects (font (size 0.7 0.7) (thickness 0.15)) (justify left bottom))
    )
    (fp_text user "${REFERENCE}" (at -0.95 3.168 180) (layer "F.Fab") hide
      (effects (font (size 0.7 0.7) (thickness 0.15)) (justify left bottom))
    )
    (fp_rect (start -0.93 -0.47) (end 0.93 0.47) (layer "F.CrtYd") (width 0.05) (fill none))
    (fp_rect (start -0.5 -0.25) (end 0.5 0.25) (layer "F.Fab") (width 0.15) (fill none))
    (pad "1" smd roundrect (at -0.485 0 180) (size 0.59 0.64) (layers "F.Cu" "F.Paste" "F.Mask") (roundrect_rratio 0.25)
      (net 397 "Net-(R69-Pad1)") (pintype "passive"))
    (pad "2" smd roundrect (at 0.485 0 180) (size 0.59 0.64) (layers "F.Cu" "F.Paste" "F.Mask") (roundrect_rratio 0.25)
      (net 1 "GND") (pintype "passive"))
  )
	(footprint "sa800u-baseboard-hw-footprints:R_0603_1608Metric" (layer "F.Cu")
    (tedit 5D5D3E92)
    (at 117.6 93.5 180)
    (descr "Resistor SMD 0603")
    (tags "resistor SMD 0603")
    (property "Author" "Antmicro")
    (property "Current" "1A")
    (property "DNP" "DNP")
    (property "License" "Apache-2.0")
    (property "MPN" "CR0603-J/-000ELF")
    (property "Manufacturer" "Bourns")
    (property "Sheetfile" "camera-interface.kicad_sch")
    (property "Sheetname" "Camera Interface")
    (property "Tolerance" "")
    (property "Val" "0R")
    (attr exclude_from_pos_files)
    (fp_text reference "R85" (at 1.05 -1.38 180) (layer "F.SilkS")
      (effects (font (size 0.7 0.7) (thickness 0.15)) (justify left bottom))
    )
    (fp_text value "R_0R_0603" (at 0 1.6 180) (layer "F.Fab")
      (effects (font (size 0.7 0.7) (thickness 0.15)) (justify left bottom))
    )
    (fp_text user "License: Apache-2.0" (at -1.25 5.9 180) (layer "F.Fab") hide
      (effects (font (size 0.7 0.7) (thickness 0.15)) (justify left bottom))
    )
    (fp_text user "Author: Antmicro" (at -1.25 4.9 180) (layer "F.Fab") hide
      (effects (font (size 0.7 0.7) (thickness 0.15)) (justify left bottom))
    )
    (fp_text user "${REFERENCE}" (at -1.25 3.898 180) (layer "F.Fab") hide
      (effects (font (size 0.7 0.7) (thickness 0.15)) (justify left bottom))
    )
    (fp_line (start -0.3 -0.3) (end 0.3 -0.3) (layer "F.SilkS") (width 0.15))
    (fp_line (start -0.3 0.3) (end 0.3 0.3) (layer "F.SilkS") (width 0.15))
    (fp_rect (start -1.25 -0.7) (end 1.25 0.7) (layer "F.CrtYd") (width 0.05) (fill none))
    (fp_rect (start -0.8 -0.4) (end 0.8 0.4) (layer "F.Fab") (width 0.15) (fill none))
    (pad "1" smd roundrect (at -0.7 0 180) (size 0.6 0.8) (layers "F.Cu" "F.Paste" "F.Mask") (roundrect_rratio 0.2)
      (net 353 "Net-(C108-Pad1)") (pintype "passive"))
    (pad "2" smd roundrect (at 0.7 0 180) (size 0.6 0.8) (layers "F.Cu" "F.Paste" "F.Mask") (roundrect_rratio 0.2)
      (net 231 "/Camera Interface/3V3_CAM") (pintype "passive"))
  )
	(footprint "sa800u-baseboard-hw-footprints:SOT-223" (layer "F.Cu")
    (tedit 5D5D462E)
    (at 118.3 99.45)
    (property "Author" "Antmicro")
    (property "DNP" "DNP")
    (property "License" "Apache-2.0")
    (property "MPN" "AP2114H-3.3TRG1")
    (property "Manufacturer" "Diodes Incorporated")
    (property "Sheetfile" "camera-interface.kicad_sch")
    (property "Sheetname" "Camera Interface")
    (attr exclude_from_pos_files)
    (fp_text reference "U12" (at 1.99 -2.15) (layer "F.SilkS")
      (effects (font (size 0.7 0.7) (thickness 0.15)) (justify left bottom))
    )
    (fp_text value "AP2114H-3.3TRG1" (at 0 5.3) (layer "F.Fab")
      (effects (font (size 0.7 0.7) (thickness 0.15)) (justify left bottom))
    )
    (fp_text user "Author: Antmicro" (at -3.451 8.849) (layer "F.Fab") hide
      (effects (font (size 0.7 0.7) (thickness 0.15)) (justify left bottom))
    )
    (fp_text user "License: Apache-2.0" (at -3.451 10.048) (layer "F.Fab") hide
      (effects (font (size 0.7 0.7) (thickness 0.15)) (justify left bottom))
    )
    (fp_text user "${REFERENCE}" (at -3.451 7.65) (layer "F.Fab") hide
      (effects (font (size 0.7 0.7) (thickness 0.15)) (justify left bottom))
    )
    (fp_line (start 3.273 1.773) (end 2.825 1.773) (layer "F.SilkS") (width 0.15))
    (fp_line (start -3.275 1.449) (end -2.976 1.773) (layer "F.SilkS") (width 0.15))
    (fp_line (start -2.976 1.773) (end -2.976 1.969) (layer "F.SilkS") (width 0.15))
    (fp_line (start 2.898 -1.776) (end 3.273 -1.776) (layer "F.SilkS") (width 0.15))
    (fp_line (start -2.775 -1.776) (end -3.275 -1.776) (layer "F.SilkS") (width 0.15))
    (fp_line (start -3.275 0.973) (end -3.275 1.449) (layer "F.SilkS") (width 0.15))
    (fp_line (start 3.273 -1.776) (end 3.273 -1.476) (layer "F.SilkS") (width 0.15))
    (fp_line (start -3.275 -1.776) (end -3.275 -1.375) (layer "F.SilkS") (width 0.15))
    (fp_line (start 3.273 1.3) (end 3.273 1.773) (layer "F.SilkS") (width 0.15))
    (fp_circle (center -3.3 2.6) (end -3.25 2.6) (layer "F.SilkS") (width 0.15) (fill solid))
    (fp_line (start -2 -4.3) (end -2 -2) (layer "F.CrtYd") (width 0.05))
    (fp_line (start 3.5 -2) (end 3.5 4.3) (layer "F.CrtYd") (width 0.05))
    (fp_line (start -3.5 4.3) (end 3.5 4.3) (layer "F.CrtYd") (width 0.05))
    (fp_line (start -3.5 -2) (end -3.5 4.3) (layer "F.CrtYd") (width 0.05))
    (fp_line (start 3.5 -2) (end 2 -2) (layer "F.CrtYd") (width 0.05))
    (fp_line (start 2 -4.3) (end 2 -2) (layer "F.CrtYd") (width 0.05))
    (fp_line (start -2 -2) (end -3.5 -2) (layer "F.CrtYd") (width 0.05))
    (fp_line (start 2 -4.3) (end -2 -4.3) (layer "F.CrtYd") (width 0.05))
    (fp_line (start -3.15 1.35) (end -2.875 1.648) (layer "F.Fab") (width 0.15))
    (fp_line (start -3.15 -1.651) (end 3.148 -1.651) (layer "F.Fab") (width 0.15))
    (fp_line (start 3.148 1.648) (end -2.875 1.648) (layer "F.Fab") (width 0.15))
    (fp_line (start 3.148 -1.651) (end 3.148 1.648) (layer "F.Fab") (width 0.15))
    (fp_line (start -3.15 1.35) (end -3.15 -1.651) (layer "F.Fab") (width 0.15))
    (pad "1" smd rect (at -2.301 3.148) (size 1.5 2.2) (layers "F.Cu" "F.Paste" "F.Mask")
      (net 1 "GND") (pinfunction "GND") (pintype "power_in"))
    (pad "2" smd rect (at 0 3.148) (size 1.5 2.2) (layers "F.Cu" "F.Paste" "F.Mask")
      (net 353 "Net-(C108-Pad1)") (pinfunction "VOUT") (pintype "output"))
    (pad "3" smd rect (at 2.298 3.148) (size 1.5 2.2) (layers "F.Cu" "F.Paste" "F.Mask")
      (net 133 "5V_SYS") (pinfunction "IN") (pintype "input"))
    (pad "4" smd rect (at 0 -3.15) (size 3.8 2.2) (layers "F.Cu" "F.Paste" "F.Mask")
      (net 353 "Net-(C108-Pad1)") (pinfunction "VOUT") (pintype "passive"))
  )
	(footprint "sa800u-baseboard-hw-footprints:C_0402_1005Metric" (layer "F.Cu")
    (tedit 616D63CF)
    (at 145.2 95.9 180)
    (descr "Capacitor SMD 0402")
    (tags "capacitor SMD 0402")
    (property "Author" "Antmicro")
    (property "Dielectric" "X5R")
    (property "License" "Apache-2.0")
    (property "MPN" "GRM155R61H104KE14D")
    (property "Manufacturer" "Murata")
    (property "Sheetfile" "m2.kicad_sch")
    (property "Sheetname" "M2")
    (property "Val" "100n")
    (property "Voltage" "50V")
    (attr smd)
    (fp_text reference "C116" (at 3.74 -0.37 180) (layer "F.SilkS")
      (effects (font (size 0.7 0.7) (thickness 0.15)) (justify left bottom))
    )
    (fp_text value "C_100n_0402" (at 0 1.4 180) (layer "F.Fab")
      (effects (font (size 0.7 0.7) (thickness 0.15)) (justify left bottom))
    )
    (fp_text user "License: Apache-2.0" (at -0.932 5.17 180) (layer "F.Fab") hide
      (effects (font (size 0.7 0.7) (thickness 0.15)) (justify left bottom))
    )
    (fp_text user "${REFERENCE}" (at -0.932 3.168 180) (layer "F.Fab") hide
      (effects (font (size 0.7 0.7) (thickness 0.15)) (justify left bottom))
    )
    (fp_text user "Author: Antmicro" (at -0.932 4.17 180) (layer "F.Fab") hide
      (effects (font (size 0.7 0.7) (thickness 0.15)) (justify left bottom))
    )
    (fp_rect (start -0.94 -0.47) (end 0.94 0.47) (layer "F.CrtYd") (width 0.05) (fill none))
    (fp_rect (start -0.499 -0.249) (end 0.499 0.249) (layer "F.Fab") (width 0.15) (fill none))
    (pad "1" smd roundrect (at -0.484 0 180) (size 0.59 0.64) (layers "F.Cu" "F.Paste" "F.Mask") (roundrect_rratio 0.25)
      (net 111 "/M2/C_PCIE0_TX0_N") (pintype "passive"))
    (pad "2" smd roundrect (at 0.484 0 180) (size 0.59 0.64) (layers "F.Cu" "F.Paste" "F.Mask") (roundrect_rratio 0.25)
      (net 110 "PCIE0_TX_N") (pintype "passive"))
  )
)
